# BASEBOARD_FAB2 (Tioga Pass) — schematic netlist excerpt (pin names and nets, part order shuffled) for the footprints in the layout excerpt that follows; sources: Cadence DE-HDL packaged netlist, KiCad conversion of Wiwynn_Tioga_Pass_MB.brd

C831  CAP  0.22UF 16V 10% X7R  pkg 0402  page 244 : A = P3E_CPU0_PE1_PCH_TXP<15> ; B = P3E_CPU0_PE1_PCH_CON_TXP<15>
C8A13  CAP  47UF 4V 20% X6S  pkg 0805  page 131 : A = P1V05_PCH_STBY ; B = GND
C1D22  CAP_A  0.1UF 16V 10% EMPTY  pkg 0402V  page 200 : A = A_HSC_MON ; B = A_HSC_MOP

(kicad_pcb
	(version 20260206)
	(generator "pcbnew")
	(generator_version "10.0")
	(general
		(thickness 1.6)
		(legacy_teardrops no)
	)
	(paper "A4")
	(title_block
		(title "Wiwynn_Tioga_Pass_MB.brd")
		(comment 1 "Tioga Pass / footprints 753-755 of 4770")
	)
	(layers
		(0 "F.Cu" signal "TOP")
		(4 "In1.Cu" signal "L2GND")
		(6 "In2.Cu" signal "L3")
		(8 "In3.Cu" signal "L4GND")
		(10 "In4.Cu" signal "L5")
		(12 "In5.Cu" signal "L6GND")
		(14 "In6.Cu" signal "L7VCC")
		(16 "In7.Cu" signal "L8VCC")
		(18 "In8.Cu" signal "L9GND")
		(20 "In9.Cu" signal "L10")
		(22 "In10.Cu" signal "L11GND")
		(24 "In11.Cu" signal "L12")
		(26 "In12.Cu" signal "L13GND")
		(2 "B.Cu" signal "BOTTOM")
		(9 "F.Adhes" user "F.Adhesive")
		(11 "B.Adhes" user "B.Adhesive")
		(13 "F.Paste" user "Package Geometry/Pastemask Top")
		(15 "B.Paste" user "Package Geometry/Pastemask Bottom")
		(5 "F.SilkS" user "Ref Des/Silkscreen Top")
		(7 "B.SilkS" user "Ref Des/Silkscreen Bottom")
		(1 "F.Mask" user "Board Geometry/Soldermask Top")
		(3 "B.Mask" user "Board Geometry/Soldermask Bottom")
		(17 "Dwgs.User" user "User.Drawings")
		(19 "Cmts.User" user "User.Comments")
		(21 "Eco1.User" user "User.Eco1")
		(23 "Eco2.User" user "User.Eco2")
		(25 "Edge.Cuts" user "Board Geometry/Outline")
		(27 "Margin" user)
		(31 "F.CrtYd" user "Package Geometry/Place Bound Top")
		(29 "B.CrtYd" user "Package Geometry/Place Bound Bottom")
		(35 "F.Fab" user "Ref Des/Assembly Top")
		(33 "B.Fab" user "Ref Des/Assembly Bottom")
	)
	(footprint ""
		(layer "F.Cu")
		(at 320.6115 -123.317 -90)
		(property "Reference" "C831"
			(at -0.8382 -0.67818 270)
			(unlocked yes)
			(layer "F.SilkS")
			(effects
				(font
					(size 0.4064 0.254)
					(thickness 0.1524)
				)
				(justify left)
			)
		)
		(property "Value" ""
			(at 0 0 270)
			(layer "F.Fab")
			(effects
				(font
					(size 1.27 1.27)
				)
			)
		)
		(duplicate_pad_numbers_are_jumpers no)
		(fp_poly
			(pts
				(xy 0.3048 -0.1016) (xy 0.3048 0.9906) (xy -0.3048 0.9906) (xy -0.3048 -0.1016)
			)
			(stroke
				(width 0)
				(type default)
			)
			(fill no)
			(layer "F.CrtYd")
		)
		(fp_line
			(start -0.3048 0.9906)
			(end 0.3048 0.9906)
			(stroke
				(width 0.1)
				(type default)
			)
			(layer "F.Fab")
		)
		(fp_line
			(start 0.3048 0.9906)
			(end 0.3048 -0.1016)
			(stroke
				(width 0.1)
				(type default)
			)
			(layer "F.Fab")
		)
		(fp_line
			(start -0.3048 -0.1016)
			(end -0.3048 0.9906)
			(stroke
				(width 0.1)
				(type default)
			)
			(layer "F.Fab")
		)
		(fp_line
			(start 0.3048 -0.1016)
			(end -0.3048 -0.1016)
			(stroke
				(width 0.1)
				(type default)
			)
			(layer "F.Fab")
		)
		(pad "1" smd rect
			(at 0 0 270)
			(size 0.508 0.508)
			(layers "F.Cu" "F.Mask" "F.Paste")
			(net "P3E_CPU0_PE1_PCH_TXP<15>")
		)
		(pad "2" smd rect
			(at 0 0.889 270)
			(size 0.508 0.508)
			(layers "F.Cu" "F.Mask" "F.Paste")
			(net "P3E_CPU0_PE1_PCH_CON_TXP<15>")
		)
		(zone
			(layer "F.Cu")
			(hatch none 0.5)
			(connect_pads
				(clearance 0)
			)
			(min_thickness 0.25)
			(keepout
				(tracks not_allowed)
				(vias allowed)
				(pads allowed)
				(copperpour not_allowed)
				(footprints allowed)
			)
			(placement
				(enabled no)
				(sheetname "")
			)
			(fill
				(thermal_gap 0.5)
				(thermal_bridge_width 0.5)
				(island_removal_mode 0)
			)
			(polygon
				(pts
					(xy 319.9765 -123.571) (xy 319.9765 -123.063) (xy 320.3575 -123.063) (xy 320.3575 -123.571)
				)
			)
		)
		(zone
			(layer "F.Cu")
			(hatch none 0.5)
			(connect_pads
				(clearance 0)
			)
			(min_thickness 0.25)
			(keepout
				(tracks allowed)
				(vias not_allowed)
				(pads allowed)
				(copperpour not_allowed)
				(footprints allowed)
			)
			(placement
				(enabled no)
				(sheetname "")
			)
			(fill
				(thermal_gap 0.5)
				(thermal_bridge_width 0.5)
				(island_removal_mode 0)
			)
			(polygon
				(pts
					(xy 320.3575 -123.571) (xy 320.3575 -123.063) (xy 319.9765 -123.063) (xy 319.9765 -123.571)
				)
			)
		)
	)
	(footprint ""
		(layer "F.Cu")
		(at 394.457682 -144.255998 90)
		(property "Reference" "C8A13"
			(at 0 0 90)
			(layer "F.SilkS")
			(hide yes)
			(effects
				(font
					(size 1.27 1.27)
				)
			)
		)
		(property "Value" ""
			(at 0 0 90)
			(layer "F.Fab")
			(effects
				(font
					(size 1.27 1.27)
				)
			)
		)
		(duplicate_pad_numbers_are_jumpers no)
		(fp_poly
			(pts
				(xy -0.7239 -0.2159) (xy 0.7239 -0.2159) (xy 0.7239 1.9939) (xy -0.7239 1.9939)
			)
			(stroke
				(width 0)
				(type default)
			)
			(fill no)
			(layer "F.CrtYd")
		)
		(fp_line
			(start 0.7239 -0.2159)
			(end -0.7239 -0.2159)
			(stroke
				(width 0.1)
				(type default)
			)
			(layer "F.Fab")
		)
		(fp_line
			(start -0.7239 -0.2159)
			(end -0.7239 1.9939)
			(stroke
				(width 0.1)
				(type default)
			)
			(layer "F.Fab")
		)
		(fp_line
			(start 0.7239 1.9939)
			(end 0.7239 -0.2159)
			(stroke
				(width 0.1)
				(type default)
			)
			(layer "F.Fab")
		)
		(fp_line
			(start -0.7239 1.9939)
			(end 0.7239 1.9939)
			(stroke
				(width 0.1)
				(type default)
			)
			(layer "F.Fab")
		)
		(pad "1" smd rect
			(at 0 0 90)
			(size 1.27 1.016)
			(layers "F.Cu" "F.Mask" "F.Paste")
			(net "P1V05_PCH_STBY")
		)
		(pad "2" smd rect
			(at 0 1.778 90)
			(size 1.27 1.016)
			(layers "F.Cu" "F.Mask" "F.Paste")
			(net "GND")
		)
		(zone
			(layer "F.Cu")
			(hatch none 0.5)
			(connect_pads
				(clearance 0)
			)
			(min_thickness 0.25)
			(keepout
				(tracks not_allowed)
				(vias allowed)
				(pads allowed)
				(copperpour not_allowed)
				(footprints allowed)
			)
			(placement
				(enabled no)
				(sheetname "")
			)
			(fill
				(thermal_gap 0.5)
				(thermal_bridge_width 0.5)
				(island_removal_mode 0)
			)
			(polygon
				(pts
					(xy 394.965682 -143.620998) (xy 394.965682 -144.890998) (xy 395.727682 -144.890998) (xy 395.727682 -143.620998)
				)
			)
		)
	)
	(footprint ""
		(layer "F.Cu")
		(at 15.875 -71.247 -90)
		(property "Reference" "C1D22"
			(at 0 0 270)
			(layer "F.SilkS")
			(hide yes)
			(effects
				(font
					(size 1.27 1.27)
				)
			)
		)
		(property "Value" ""
			(at 0 0 270)
			(layer "F.Fab")
			(effects
				(font
					(size 1.27 1.27)
				)
			)
		)
		(duplicate_pad_numbers_are_jumpers no)
		(fp_rect
			(start 0.3048 0.9906)
			(end -0.3048 -0.1016)
			(stroke
				(width 0)
				(type default)
			)
			(fill no)
			(layer "F.CrtYd")
		)
		(fp_line
			(start -0.3048 0.9906)
			(end 0.3048 0.9906)
			(stroke
				(width 0.1)
				(type default)
			)
			(layer "F.Fab")
		)
		(fp_line
			(start 0.3048 0.9906)
			(end 0.3048 -0.1016)
			(stroke
				(width 0.1)
				(type default)
			)
			(layer "F.Fab")
		)
		(fp_line
			(start -0.3048 -0.1016)
			(end -0.3048 0.9906)
			(stroke
				(width 0.1)
				(type default)
			)
			(layer "F.Fab")
		)
		(fp_line
			(start 0.3048 -0.1016)
			(end -0.3048 -0.1016)
			(stroke
				(width 0.1)
				(type default)
			)
			(layer "F.Fab")
		)
		(pad "1" smd rect
			(at 0 0 270)
			(size 0.508 0.508)
			(layers "F.Cu" "F.Mask" "F.Paste")
			(net "A_HSC_MON")
		)
		(pad "2" smd rect
			(at 0 0.889 270)
			(size 0.508 0.508)
			(layers "F.Cu" "F.Mask" "F.Paste")
			(net "A_HSC_MOP")
		)
		(zone
			(layer "F.Cu")
			(hatch none 0.5)
			(connect_pads
				(clearance 0)
			)
			(min_thickness 0.25)
			(keepout
				(tracks allowed)
				(vias not_allowed)
				(pads allowed)
				(copperpour not_allowed)
				(footprints allowed)
			)
			(placement
				(enabled no)
				(sheetname "")
			)
			(fill
				(thermal_gap 0.5)
				(thermal_bridge_width 0.5)
				(island_removal_mode 0)
			)
			(polygon
				(pts
					(xy 15.24 -70.993) (xy 15.621 -70.993) (xy 15.621 -71.501) (xy 15.24 -71.501)
				)
			)
		)
		(zone
			(layer "F.Cu")
			(hatch none 0.5)
			(connect_pads
				(clearance 0)
			)
			(min_thickness 0.25)
			(keepout
				(tracks not_allowed)
				(vias allowed)
				(pads allowed)
				(copperpour not_allowed)
				(footprints allowed)
			)
			(placement
				(enabled no)
				(sheetname "")
			)
			(fill
				(thermal_gap 0.5)
				(thermal_bridge_width 0.5)
				(island_removal_mode 0)
			)
			(polygon
				(pts
					(xy 15.24 -70.993) (xy 15.621 -70.993) (xy 15.621 -71.501) (xy 15.24 -71.501)
				)
			)
		)
	)
)
